(kicad_pcb
	(version 20260206)
	(generator "pcbnew")
	(generator_version "10.0")
	(general
		(thickness 1.6)
		(legacy_teardrops no)
	)
	(paper "A4")
	(title_block
		(title "v2-tray-backplane — ms_tbp_v2.brd")
		(comment 1 "Open CloudServer (Microsoft) / footprints 9-14 of 164")
	)
	(layers
		(0 "F.Cu" signal "TOP")
		(4 "In1.Cu" signal "LYR2")
		(6 "In2.Cu" signal "LYR3")
		(8 "In3.Cu" signal "LYR4")
		(10 "In4.Cu" signal "LYR5")
		(12 "In5.Cu" signal "LYR6")
		(14 "In6.Cu" signal "LYR7")
		(2 "B.Cu" signal "BOTTOM")
		(9 "F.Adhes" user "F.Adhesive")
		(11 "B.Adhes" user "B.Adhesive")
		(13 "F.Paste" user "Package Geometry/Pastemask Top")
		(15 "B.Paste" user "Package Geometry/Pastemask Bottom")
		(5 "F.SilkS" user "Ref Des/Silkscreen Top")
		(7 "B.SilkS" user "Ref Des/Silkscreen Bottom")
		(1 "F.Mask" user "Board Geometry/Soldermask Top")
		(3 "B.Mask" user "Board Geometry/Soldermask Bottom")
		(17 "Dwgs.User" user "User.Drawings")
		(19 "Cmts.User" user "User.Comments")
		(21 "Eco1.User" user "User.Eco1")
		(23 "Eco2.User" user "User.Eco2")
		(25 "Edge.Cuts" user "Board Geometry/Outline")
		(27 "Margin" user)
		(31 "F.CrtYd" user "Package Geometry/Place Bound Top")
		(29 "B.CrtYd" user "Package Geometry/Place Bound Bottom")
		(35 "F.Fab" user "Ref Des/Assembly Top")
		(33 "B.Fab" user "Ref Des/Assembly Bottom")
	)
	(footprint ""
		(layer "F.Cu")
		(at -300.99 10.287)
		(property "Reference" "R12"
			(at -3.175 0.0381 0)
			(unlocked yes)
			(layer "F.SilkS")
			(effects
				(font
					(size 0.762 0.5334)
					(thickness 0.1016)
				)
			)
		)
		(property "Value" ""
			(at 0 0 0)
			(layer "F.Fab")
			(effects
				(font
					(size 1.27 1.27)
				)
			)
		)
		(duplicate_pad_numbers_are_jumpers no)
		(fp_line
			(start 0 -0.381)
			(end 0 0.381)
			(stroke
				(width 0.127)
				(type default)
			)
			(layer "F.SilkS")
		)
		(fp_poly
			(pts
				(xy 1.255601 0.6564) (xy -1.255601 0.6564) (xy -1.255601 -0.656399) (xy 1.255601 -0.656399)
			)
			(stroke
				(width 0)
				(type default)
			)
			(fill no)
			(layer "F.CrtYd")
		)
		(fp_line
			(start -0.800001 -0.399999)
			(end -0.800001 0.399999)
			(stroke
				(width 0.1)
				(type default)
			)
			(layer "F.Fab")
		)
		(fp_line
			(start -0.800001 0.399999)
			(end 0.800001 0.399999)
			(stroke
				(width 0.1)
				(type default)
			)
			(layer "F.Fab")
		)
		(fp_line
			(start 0.800001 -0.399999)
			(end -0.800001 -0.399999)
			(stroke
				(width 0.1)
				(type default)
			)
			(layer "F.Fab")
		)
		(fp_line
			(start 0.800001 0.399999)
			(end 0.800001 -0.399999)
			(stroke
				(width 0.1)
				(type default)
			)
			(layer "F.Fab")
		)
		(pad "1" smd rect
			(at -0.650001 0)
			(size 0.7112 0.8128)
			(layers "F.Cu" "F.Mask" "F.Paste")
			(net "BLADE_B1_MATED_N<1>")
		)
		(pad "2" smd rect
			(at 0.650001 0 180)
			(size 0.7112 0.8128)
			(layers "F.Cu" "F.Mask" "F.Paste")
			(net "GND")
		)
	)
	(footprint ""
		(layer "F.Cu")
		(at -266.446 7.4676 180)
		(property "Reference" "FB8"
			(at -1.651 -0.0635 0)
			(unlocked yes)
			(layer "F.SilkS")
			(effects
				(font
					(size 0.762 0.5334)
					(thickness 0.1016)
				)
				(justify left)
			)
		)
		(property "Value" ""
			(at 0 0 180)
			(layer "F.Fab")
			(effects
				(font
					(size 1.27 1.27)
				)
			)
		)
		(duplicate_pad_numbers_are_jumpers no)
		(fp_poly
			(pts
				(xy -1.016 0.508) (xy -1.016 -0.508) (xy 1.016 -0.508) (xy 1.016 0.508)
			)
			(stroke
				(width 0)
				(type default)
			)
			(fill no)
			(layer "F.CrtYd")
		)
		(fp_line
			(start 0.508 0.254)
			(end -0.508 0.254)
			(stroke
				(width 0.1)
				(type default)
			)
			(layer "F.Fab")
		)
		(fp_line
			(start 0.508 -0.254)
			(end 0.508 0.254)
			(stroke
				(width 0.1)
				(type default)
			)
			(layer "F.Fab")
		)
		(fp_line
			(start -0.508 0.254)
			(end -0.508 -0.254)
			(stroke
				(width 0.1)
				(type default)
			)
			(layer "F.Fab")
		)
		(fp_line
			(start -0.508 -0.254)
			(end 0.508 -0.254)
			(stroke
				(width 0.1)
				(type default)
			)
			(layer "F.Fab")
		)
		(pad "1" smd rect
			(at -0.4572 0 270)
			(size 0.508 0.5842)
			(layers "F.Cu" "F.Mask" "F.Paste")
			(net "UNNAMED_16_FERRITE_I115_A")
		)
		(pad "2" smd rect
			(at 0.4572 0 270)
			(size 0.508 0.5842)
			(layers "F.Cu" "F.Mask" "F.Paste")
			(net "P3V3_40G_B1_VCC_TX")
		)
	)
	(footprint ""
		(layer "F.Cu")
		(at -47.663001 12.789002 90)
		(property "Reference" "C17"
			(at -2.644038 0.027841 90)
			(unlocked yes)
			(layer "F.SilkS")
			(effects
				(font
					(size 0.762 0.5334)
					(thickness 0.1016)
				)
			)
		)
		(property "Value" ""
			(at 0 0 90)
			(layer "F.Fab")
			(effects
				(font
					(size 1.27 1.27)
				)
			)
		)
		(duplicate_pad_numbers_are_jumpers no)
		(fp_poly
			(pts
				(xy -0.999299 0.504) (xy -0.999299 -0.503999) (xy 0.9993 -0.503999) (xy 0.9993 0.504)
			)
			(stroke
				(width 0)
				(type default)
			)
			(fill no)
			(layer "F.CrtYd")
		)
		(fp_line
			(start 0.499999 -0.249999)
			(end 0.499999 0.25)
			(stroke
				(width 0.1)
				(type default)
			)
			(layer "F.Fab")
		)
		(fp_line
			(start -0.499999 -0.249999)
			(end 0.499999 -0.249999)
			(stroke
				(width 0.1)
				(type default)
			)
			(layer "F.Fab")
		)
		(fp_line
			(start 0.499999 0.25)
			(end -0.499999 0.25)
			(stroke
				(width 0.1)
				(type default)
			)
			(layer "F.Fab")
		)
		(fp_line
			(start -0.499999 0.25)
			(end -0.499999 -0.249999)
			(stroke
				(width 0.1)
				(type default)
			)
			(layer "F.Fab")
		)
		(pad "1" smd rect
			(at -0.4572 0 180)
			(size 0.508 0.5842)
			(layers "F.Cu" "F.Mask" "F.Paste")
			(net "P3V3_40G_B2_VCC1")
		)
		(pad "2" smd rect
			(at 0.4572 0 180)
			(size 0.508 0.5842)
			(layers "F.Cu" "F.Mask" "F.Paste")
			(net "GND")
		)
	)
	(footprint ""
		(layer "F.Cu")
		(at -334.449001 21.171002 90)
		(property "Reference" "C1"
			(at -0.672998 1.366101 90)
			(unlocked yes)
			(layer "F.SilkS")
			(effects
				(font
					(size 0.762 0.5334)
					(thickness 0.1016)
				)
			)
		)
		(property "Value" ""
			(at 0 0 90)
			(layer "F.Fab")
			(effects
				(font
					(size 1.27 1.27)
				)
			)
		)
		(duplicate_pad_numbers_are_jumpers no)
		(fp_line
			(start 0 -0.381)
			(end 0 0.381)
			(stroke
				(width 0.127)
				(type default)
			)
			(layer "F.SilkS")
		)
		(fp_poly
			(pts
				(xy 1.2533 0.6564) (xy -1.253299 0.6564) (xy -1.253299 -0.656399) (xy 1.2533 -0.656399)
			)
			(stroke
				(width 0)
				(type default)
			)
			(fill no)
			(layer "F.CrtYd")
		)
		(fp_line
			(start 0.762 -0.381)
			(end -0.762 -0.381)
			(stroke
				(width 0.1)
				(type default)
			)
			(layer "F.Fab")
		)
		(fp_line
			(start -0.762 -0.381)
			(end -0.762 0.381)
			(stroke
				(width 0.1)
				(type default)
			)
			(layer "F.Fab")
		)
		(fp_line
			(start 0.762 0.381)
			(end 0.762 -0.381)
			(stroke
				(width 0.1)
				(type default)
			)
			(layer "F.Fab")
		)
		(fp_line
			(start -0.762 0.381)
			(end 0.762 0.381)
			(stroke
				(width 0.1)
				(type default)
			)
			(layer "F.Fab")
		)
		(pad "1" smd rect
			(at -0.6477 0 90)
			(size 0.7112 0.8128)
			(layers "F.Cu" "F.Mask" "F.Paste")
			(net "P12V")
		)
		(pad "2" smd rect
			(at 0.6477 0 270)
			(size 0.7112 0.8128)
			(layers "F.Cu" "F.Mask" "F.Paste")
			(net "GND")
		)
	)
	(footprint ""
		(layer "F.Cu")
		(at -48.856801 12.789002 90)
		(property "Reference" "C18"
			(at 0 -0.942899 90)
			(unlocked yes)
			(layer "F.SilkS")
			(effects
				(font
					(size 0.762 0.5334)
					(thickness 0.1016)
				)
			)
		)
		(property "Value" ""
			(at 0 0 90)
			(layer "F.Fab")
			(effects
				(font
					(size 1.27 1.27)
				)
			)
		)
		(duplicate_pad_numbers_are_jumpers no)
		(fp_line
			(start 0 -0.381)
			(end 0 0.381)
			(stroke
				(width 0.127)
				(type default)
			)
			(layer "F.SilkS")
		)
		(fp_poly
			(pts
				(xy 1.2533 0.6564) (xy -1.253299 0.6564) (xy -1.253299 -0.656399) (xy 1.2533 -0.656399)
			)
			(stroke
				(width 0)
				(type default)
			)
			(fill no)
			(layer "F.CrtYd")
		)
		(fp_line
			(start 0.762 -0.381)
			(end -0.762 -0.381)
			(stroke
				(width 0.1)
				(type default)
			)
			(layer "F.Fab")
		)
		(fp_line
			(start -0.762 -0.381)
			(end -0.762 0.381)
			(stroke
				(width 0.1)
				(type default)
			)
			(layer "F.Fab")
		)
		(fp_line
			(start 0.762 0.381)
			(end 0.762 -0.381)
			(stroke
				(width 0.1)
				(type default)
			)
			(layer "F.Fab")
		)
		(fp_line
			(start -0.762 0.381)
			(end 0.762 0.381)
			(stroke
				(width 0.1)
				(type default)
			)
			(layer "F.Fab")
		)
		(pad "1" smd rect
			(at -0.6477 0 90)
			(size 0.7112 0.8128)
			(layers "F.Cu" "F.Mask" "F.Paste")
			(net "P3V3_40G_B2_VCC1")
		)
		(pad "2" smd rect
			(at 0.6477 0 270)
			(size 0.7112 0.8128)
			(layers "F.Cu" "F.Mask" "F.Paste")
			(net "GND")
		)
	)
	(footprint ""
		(layer "F.Cu")
		(at -165.0238 31.1912 90)
		(property "Reference" "R86"
			(at 0.77216 1.60274 90)
			(unlocked yes)
			(layer "F.SilkS")
			(effects
				(font
					(size 0.762 0.5334)
					(thickness 0.1016)
				)
			)
		)
		(property "Value" ""
			(at 0 0 90)
			(layer "F.Fab")
			(effects
				(font
					(size 1.27 1.27)
				)
			)
		)
		(duplicate_pad_numbers_are_jumpers no)
		(fp_line
			(start 0 -0.381)
			(end 0 0.381)
			(stroke
				(width 0.127)
				(type default)
			)
			(layer "F.SilkS")
		)
		(fp_poly
			(pts
				(xy 1.255601 0.656399) (xy -1.255601 0.656399) (xy -1.255601 -0.6564) (xy 1.255601 -0.6564)
			)
			(stroke
				(width 0)
				(type default)
			)
			(fill no)
			(layer "F.CrtYd")
		)
		(fp_line
			(start 0.800001 -0.399999)
			(end -0.800001 -0.399999)
			(stroke
				(width 0.1)
				(type default)
			)
			(layer "F.Fab")
		)
		(fp_line
			(start -0.800001 -0.399999)
			(end -0.800001 0.399999)
			(stroke
				(width 0.1)
				(type default)
			)
			(layer "F.Fab")
		)
		(fp_line
			(start 0.800001 0.399999)
			(end 0.800001 -0.399999)
			(stroke
				(width 0.1)
				(type default)
			)
			(layer "F.Fab")
		)
		(fp_line
			(start -0.800001 0.399999)
			(end 0.800001 0.399999)
			(stroke
				(width 0.1)
				(type default)
			)
			(layer "F.Fab")
		)
		(pad "1" smd rect
			(at -0.650001 0 90)
			(size 0.7112 0.8128)
			(layers "F.Cu" "F.Mask" "F.Paste")
			(net "GND")
		)
		(pad "2" smd rect
			(at 0.650001 0 270)
			(size 0.7112 0.8128)
			(layers "F.Cu" "F.Mask" "F.Paste")
			(net "BLADE_MATED_B2_N<0>")
		)
	)
)
